# T6G (Grand Teton) — schematic netlist excerpt (pin names and nets, part order shuffled) for the footprints in the layout excerpt that follows; sources: Cadence DE-HDL packaged netlist, KiCad conversion of 04192023_DAF0TMB3IC0_F0TG_MB_C_brd_V02_OCP.brd

C7003  Q_CAP  47UF 4V 20% X6S  pkg C0805  page 279 : A = P0V9_CPU0_RT_2D ; B = GND
R1414  Q_RES  10K 1% CHIP  pkg 0201LF  page 309 : A = RXDET_BYP_RT_CPU0_P3 ; B = GND

(kicad_pcb
	(version 20260206)
	(generator "pcbnew")
	(generator_version "10.0")
	(general
		(thickness 1.6)
		(legacy_teardrops no)
	)
	(paper "A4")
	(title_block
		(title "04192023_DAF0TMB3IC0_F0TG_MB_C_brd_V02_OCP.brd")
		(comment 1 "Grand Teton / footprints 750-751 of 8354")
	)
	(layers
		(0 "F.Cu" signal "TOP")
		(4 "In1.Cu" signal "GND")
		(6 "In2.Cu" signal "IN1")
		(8 "In3.Cu" signal "GND1")
		(10 "In4.Cu" signal "IN2")
		(12 "In5.Cu" signal "GND2")
		(14 "In6.Cu" signal "IN3")
		(16 "In7.Cu" signal "GND3")
		(18 "In8.Cu" signal "VCC")
		(20 "In9.Cu" signal "VCC1")
		(22 "In10.Cu" signal "GND4")
		(24 "In11.Cu" signal "IN4")
		(26 "In12.Cu" signal "GND5")
		(28 "In13.Cu" signal "IN5")
		(30 "In14.Cu" signal "GND6")
		(32 "In15.Cu" signal "IN6")
		(34 "In16.Cu" signal "GND7")
		(2 "B.Cu" signal "BOTTOM")
		(9 "F.Adhes" user "F.Adhesive")
		(11 "B.Adhes" user "B.Adhesive")
		(13 "F.Paste" user "Package Geometry/Pastemask Top")
		(15 "B.Paste" user "Package Geometry/Pastemask Bottom")
		(5 "F.SilkS" user "Ref Des/Silkscreen Top")
		(7 "B.SilkS" user "Ref Des/Silkscreen Bottom")
		(1 "F.Mask" user "Board Geometry/Soldermask Top")
		(3 "B.Mask" user "Board Geometry/Soldermask Bottom")
		(17 "Dwgs.User" user "User.Drawings")
		(19 "Cmts.User" user "User.Comments")
		(21 "Eco1.User" user "User.Eco1")
		(23 "Eco2.User" user "User.Eco2")
		(25 "Edge.Cuts" user "Board Geometry/Outline")
		(27 "Margin" user)
		(31 "F.CrtYd" user "Package Geometry/Place Bound Top")
		(29 "B.CrtYd" user "Package Geometry/Place Bound Bottom")
		(35 "F.Fab" user "Ref Des/Assembly Top")
		(33 "B.Fab" user "Ref Des/Assembly Bottom")
	)
	(footprint ""
		(layer "F.Cu")
		(at 329.17384 -410.248608 90)
		(property "Reference" "C7003"
			(at 0 0 90)
			(layer "F.SilkS")
			(hide yes)
			(effects
				(font
					(size 1.27 1.27)
				)
			)
		)
		(property "Value" ""
			(at 0 0 90)
			(layer "F.Fab")
			(effects
				(font
					(size 1.27 1.27)
				)
			)
		)
		(duplicate_pad_numbers_are_jumpers no)
		(fp_line
			(start 1.524 -0.762)
			(end 1.524 0.762)
			(stroke
				(width 0.1524)
				(type default)
			)
			(layer "F.SilkS")
		)
		(fp_line
			(start -1.524 -0.762)
			(end 1.524 -0.762)
			(stroke
				(width 0.1524)
				(type default)
			)
			(layer "F.SilkS")
		)
		(fp_line
			(start 1.524 0.762)
			(end -1.524 0.762)
			(stroke
				(width 0.1524)
				(type default)
			)
			(layer "F.SilkS")
		)
		(fp_line
			(start -1.524 0.762)
			(end -1.524 -0.762)
			(stroke
				(width 0.1524)
				(type default)
			)
			(layer "F.SilkS")
		)
		(fp_line
			(start 1.1049 -0.724916)
			(end -1.1049 -0.724916)
			(stroke
				(width 0.1)
				(type default)
			)
			(layer "F.Fab")
		)
		(fp_line
			(start -1.1049 -0.724916)
			(end -1.1049 0.724916)
			(stroke
				(width 0.1)
				(type default)
			)
			(layer "F.Fab")
		)
		(fp_line
			(start 1.1049 0.724916)
			(end 1.1049 -0.724916)
			(stroke
				(width 0.1)
				(type default)
			)
			(layer "F.Fab")
		)
		(fp_line
			(start -1.1049 0.724916)
			(end 1.1049 0.724916)
			(stroke
				(width 0.1)
				(type default)
			)
			(layer "F.Fab")
		)
		(pad "1" smd rect
			(at -0.889 0 270)
			(size 1.016 1.27)
			(layers "F.Cu" "F.Mask" "F.Paste")
			(net "P0V9_CPU0_RT_2D")
		)
		(pad "2" smd rect
			(at 0.889 0 270)
			(size 1.016 1.27)
			(layers "F.Cu" "F.Mask" "F.Paste")
			(net "GND")
		)
	)
	(footprint ""
		(layer "F.Cu")
		(at 392.797538 -398.34058)
		(property "Reference" "R1414"
			(at 0 0 0)
			(layer "F.SilkS")
			(hide yes)
			(effects
				(font
					(size 1.27 1.27)
				)
			)
		)
		(property "Value" ""
			(at 0 0 0)
			(layer "F.Fab")
			(effects
				(font
					(size 1.27 1.27)
				)
			)
		)
		(duplicate_pad_numbers_are_jumpers no)
		(fp_line
			(start -0.32512 -0.175006)
			(end 0.32512 -0.175006)
			(stroke
				(width 0.1)
				(type default)
			)
			(layer "F.Fab")
		)
		(fp_line
			(start -0.32512 0.175006)
			(end -0.32512 -0.175006)
			(stroke
				(width 0.1)
				(type default)
			)
			(layer "F.Fab")
		)
		(fp_line
			(start 0.32512 -0.175006)
			(end 0.32512 0.175006)
			(stroke
				(width 0.1)
				(type default)
			)
			(layer "F.Fab")
		)
		(fp_line
			(start 0.32512 0.175006)
			(end -0.32512 0.175006)
			(stroke
				(width 0.1)
				(type default)
			)
			(layer "F.Fab")
		)
		(pad "1" smd rect
			(at -0.2667 0)
			(size 0.3048 0.381)
			(layers "F.Cu" "F.Mask" "F.Paste")
			(net "RXDET_BYP_RT_CPU0_P3")
		)
		(pad "2" smd rect
			(at 0.2667 0 180)
			(size 0.3048 0.381)
			(layers "F.Cu" "F.Mask" "F.Paste")
			(net "GND")
		)
	)
)
